# T6G (Grand Teton) — schematic netlist excerpt (pin names and nets, part order shuffled) for the footprints in the layout excerpt that follows; sources: Cadence DE-HDL packaged netlist, KiCad conversion of 04192023_DAF0TMB3IC0_F0TG_MB_C_brd_V02_OCP.brd

J83  PICOPROBE_BXA  DELTA-L 4.0 EMPTY  pkg TRIANG_LAUNCH_3PXB  page 229
  \1_p\  = DELTA_L_85_10INCH_IN1_DN
  \2_n\  = DELTA_L_85_10INCH_IN1_DP
  \3_g\  = DELTA_L_GND_1

(kicad_pcb
	(version 20260206)
	(generator "pcbnew")
	(generator_version "10.0")
	(general
		(thickness 1.6)
		(legacy_teardrops no)
	)
	(paper "A4")
	(title_block
		(title "04192023_DAF0TMB3IC0_F0TG_MB_C_brd_V02_OCP.brd")
		(comment 1 "Grand Teton / footprints 768-768 of 8354")
	)
	(layers
		(0 "F.Cu" signal "TOP")
		(4 "In1.Cu" signal "GND")
		(6 "In2.Cu" signal "IN1")
		(8 "In3.Cu" signal "GND1")
		(10 "In4.Cu" signal "IN2")
		(12 "In5.Cu" signal "GND2")
		(14 "In6.Cu" signal "IN3")
		(16 "In7.Cu" signal "GND3")
		(18 "In8.Cu" signal "VCC")
		(20 "In9.Cu" signal "VCC1")
		(22 "In10.Cu" signal "GND4")
		(24 "In11.Cu" signal "IN4")
		(26 "In12.Cu" signal "GND5")
		(28 "In13.Cu" signal "IN5")
		(30 "In14.Cu" signal "GND6")
		(32 "In15.Cu" signal "IN6")
		(34 "In16.Cu" signal "GND7")
		(2 "B.Cu" signal "BOTTOM")
		(9 "F.Adhes" user "F.Adhesive")
		(11 "B.Adhes" user "B.Adhesive")
		(13 "F.Paste" user "Package Geometry/Pastemask Top")
		(15 "B.Paste" user "Package Geometry/Pastemask Bottom")
		(5 "F.SilkS" user "Ref Des/Silkscreen Top")
		(7 "B.SilkS" user "Ref Des/Silkscreen Bottom")
		(1 "F.Mask" user "Board Geometry/Soldermask Top")
		(3 "B.Mask" user "Board Geometry/Soldermask Bottom")
		(17 "Dwgs.User" user "User.Drawings")
		(19 "Cmts.User" user "User.Comments")
		(21 "Eco1.User" user "User.Eco1")
		(23 "Eco2.User" user "User.Eco2")
		(25 "Edge.Cuts" user "Board Geometry/Outline")
		(27 "Margin" user)
		(31 "F.CrtYd" user "Package Geometry/Place Bound Top")
		(29 "B.CrtYd" user "Package Geometry/Place Bound Bottom")
		(35 "F.Fab" user "Ref Des/Assembly Top")
		(33 "B.Fab" user "Ref Des/Assembly Bottom")
	)
	(footprint ""
		(layer "F.Cu")
		(at 185.862722 6.063234 180)
		(property "Reference" "J83"
			(at -4.472686 -1.101598 90)
			(unlocked yes)
			(layer "F.SilkS")
			(effects
				(font
					(size 0.7874 0.5842)
					(thickness 0.1524)
				)
				(justify left)
			)
		)
		(property "Value" ""
			(at 0 0 180)
			(layer "F.Fab")
			(effects
				(font
					(size 1.27 1.27)
				)
			)
		)
		(duplicate_pad_numbers_are_jumpers no)
		(fp_line
			(start 1.2192 2.06756)
			(end -1.2192 2.06756)
			(stroke
				(width 0.1524)
				(type default)
			)
			(layer "F.SilkS")
		)
		(fp_line
			(start 1.2192 -2.06756)
			(end 1.2192 2.06756)
			(stroke
				(width 0.1524)
				(type default)
			)
			(layer "F.SilkS")
		)
		(fp_line
			(start -1.2192 2.06756)
			(end -1.2192 -2.06756)
			(stroke
				(width 0.1524)
				(type default)
			)
			(layer "F.SilkS")
		)
		(fp_line
			(start -1.2192 -2.06756)
			(end 1.2192 -2.06756)
			(stroke
				(width 0.1524)
				(type default)
			)
			(layer "F.SilkS")
		)
		(pad "" np_thru_hole circle
			(at -2.8829 -1.27 90)
			(size 1.0414 1.0414)
			(drill 1.0414)
			(layers "*.Cu" "*.Mask")
			(clearance 0.381)
			(thermal_gap 0.381)
		)
		(pad "" np_thru_hole circle
			(at -2.8829 1.27 90)
			(size 1.0414 1.0414)
			(drill 1.0414)
			(layers "*.Cu" "*.Mask")
			(clearance 0.381)
			(thermal_gap 0.381)
		)
		(pad "" np_thru_hole circle
			(at 3.4671 -1.27 90)
			(size 1.0414 1.0414)
			(drill 1.0414)
			(layers "*.Cu" "*.Mask")
			(clearance 0.381)
			(thermal_gap 0.381)
		)
		(pad "" np_thru_hole circle
			(at 3.4671 1.27 90)
			(size 1.0414 1.0414)
			(drill 1.0414)
			(layers "*.Cu" "*.Mask")
			(clearance 0.381)
			(thermal_gap 0.381)
		)
		(pad "1" smd rect
			(at 0.8255 -0.249936 90)
			(size 0.3048 0.508)
			(layers "F.Cu" "F.Mask" "F.Paste")
			(net "DELTA_L_85_10INCH_IN1_DN")
		)
		(pad "2" smd rect
			(at 0.8255 0.249936 90)
			(size 0.3048 0.508)
			(layers "F.Cu" "F.Mask" "F.Paste")
			(net "DELTA_L_85_10INCH_IN1_DP")
		)
		(pad "3" smd circle
			(at 0 0 180)
			(size 0 0)
			(layers "F.Cu" "F.Mask" "F.Paste")
			(net "DELTA_L_GND_1")
		)
		(zone
			(layer "F.Cu")
			(hatch none 0.5)
			(connect_pads
				(clearance 0)
			)
			(min_thickness 0.25)
			(keepout
				(tracks not_allowed)
				(vias allowed)
				(pads allowed)
				(copperpour not_allowed)
				(footprints allowed)
			)
			(placement
				(enabled no)
				(sheetname "")
			)
			(fill
				(thermal_gap 0.5)
				(thermal_bridge_width 0.5)
				(island_removal_mode 0)
			)
			(polygon
				(pts
					(xy 184.745122 6.611874) (xy 184.745122 6.51637) (xy 185.342022 6.51637) (xy 185.342022 6.10997)
					(xy 184.745122 6.10997) (xy 184.745122 6.016498) (xy 185.342022 6.016498) (xy 185.342022 5.610098)
					(xy 184.745122 5.610098) (xy 184.745122 5.514594) (xy 185.443622 5.514594) (xy 185.443622 6.611874)
				)
			)
		)
		(zone
			(layers "F.Cu" "B.Cu" "In1.Cu" "In2.Cu" "In3.Cu" "In4.Cu" "In5.Cu" "In6.Cu"
				"In7.Cu" "In8.Cu" "In9.Cu" "In10.Cu" "In11.Cu" "In12.Cu" "In13.Cu" "In14.Cu"
				"In15.Cu" "In16.Cu"
			)
			(hatch none 0.5)
			(connect_pads
				(clearance 0)
			)
			(min_thickness 0.25)
			(keepout
				(tracks not_allowed)
				(vias allowed)
				(pads allowed)
				(copperpour not_allowed)
				(footprints allowed)
			)
			(placement
				(enabled no)
				(sheetname "")
			)
			(fill
				(thermal_gap 0.5)
				(thermal_bridge_width 0.5)
				(island_removal_mode 0)
			)
			(polygon
				(pts
					(arc
						(start 183.322722 4.793234)
						(mid 181.468522 4.793234)
						(end 183.322722 4.793234)
					)
				)
			)
		)
		(zone
			(layers "F.Cu" "B.Cu" "In1.Cu" "In2.Cu" "In3.Cu" "In4.Cu" "In5.Cu" "In6.Cu"
				"In7.Cu" "In8.Cu" "In9.Cu" "In10.Cu" "In11.Cu" "In12.Cu" "In13.Cu" "In14.Cu"
				"In15.Cu" "In16.Cu"
			)
			(hatch none 0.5)
			(connect_pads
				(clearance 0)
			)
			(min_thickness 0.25)
			(keepout
				(tracks not_allowed)
				(vias allowed)
				(pads allowed)
				(copperpour not_allowed)
				(footprints allowed)
			)
			(placement
				(enabled no)
				(sheetname "")
			)
			(fill
				(thermal_gap 0.5)
				(thermal_bridge_width 0.5)
				(island_removal_mode 0)
			)
			(polygon
				(pts
					(arc
						(start 183.322722 7.333234)
						(mid 181.468522 7.333234)
						(end 183.322722 7.333234)
					)
				)
			)
		)
		(zone
			(layers "F.Cu" "B.Cu" "In1.Cu" "In2.Cu" "In3.Cu" "In4.Cu" "In5.Cu" "In6.Cu"
				"In7.Cu" "In8.Cu" "In9.Cu" "In10.Cu" "In11.Cu" "In12.Cu" "In13.Cu" "In14.Cu"
				"In15.Cu" "In16.Cu"
			)
			(hatch none 0.5)
			(connect_pads
				(clearance 0)
			)
			(min_thickness 0.25)
			(keepout
				(tracks not_allowed)
				(vias allowed)
				(pads allowed)
				(copperpour not_allowed)
				(footprints allowed)
			)
			(placement
				(enabled no)
				(sheetname "")
			)
			(fill
				(thermal_gap 0.5)
				(thermal_bridge_width 0.5)
				(island_removal_mode 0)
			)
			(polygon
				(pts
					(arc
						(start 189.672722 4.793234)
						(mid 187.818522 4.793234)
						(end 189.672722 4.793234)
					)
				)
			)
		)
		(zone
			(layers "F.Cu" "B.Cu" "In1.Cu" "In2.Cu" "In3.Cu" "In4.Cu" "In5.Cu" "In6.Cu"
				"In7.Cu" "In8.Cu" "In9.Cu" "In10.Cu" "In11.Cu" "In12.Cu" "In13.Cu" "In14.Cu"
				"In15.Cu" "In16.Cu"
			)
			(hatch none 0.5)
			(connect_pads
				(clearance 0)
			)
			(min_thickness 0.25)
			(keepout
				(tracks not_allowed)
				(vias allowed)
				(pads allowed)
				(copperpour not_allowed)
				(footprints allowed)
			)
			(placement
				(enabled no)
				(sheetname "")
			)
			(fill
				(thermal_gap 0.5)
				(thermal_bridge_width 0.5)
				(island_removal_mode 0)
			)
			(polygon
				(pts
					(arc
						(start 189.672722 7.333234)
						(mid 187.818522 7.333234)
						(end 189.672722 7.333234)
					)
				)
			)
		)
	)
)
